(kicad_pcb
	(version 20221018)
	(generator pcbnew)
	(general
    (thickness 1.562)
  )
	(paper "A4")
	(title_block
    (title "Thunderbolt PCIe Adaper")
    (date "2024-07-09")
    (rev "1.0.3")
    (comment 1 "www.antmicro.com")
    (comment 2 "Antmicro Ltd.")
		(comment 9 "footprints 67-71 of 271")
	)
	(layers
    (0 "F.Cu" signal)
    (1 "In1.Cu" signal)
    (2 "In2.Cu" signal)
    (3 "In3.Cu" signal)
    (4 "In4.Cu" signal)
    (31 "B.Cu" signal)
    (32 "B.Adhes" user "B.Adhesive")
    (33 "F.Adhes" user "F.Adhesive")
    (34 "B.Paste" user)
    (35 "F.Paste" user)
    (36 "B.SilkS" user "B.Silkscreen")
    (37 "F.SilkS" user "F.Silkscreen")
    (38 "B.Mask" user)
    (39 "F.Mask" user)
    (40 "Dwgs.User" user "User.Drawings")
    (41 "Cmts.User" user "User.Comments")
    (42 "Eco1.User" user "User.Eco1")
    (43 "Eco2.User" user "User.Eco2")
    (44 "Edge.Cuts" user)
    (45 "Margin" user)
    (46 "B.CrtYd" user "B.Courtyard")
    (47 "F.CrtYd" user "F.Courtyard")
    (48 "B.Fab" user)
    (49 "F.Fab" user)
  )
	(footprint "antmicro-footprints:QFN-32-4EP_4x6mm_P0.5mm" (layer "F.Cu")
    (at 110.325 82.15)
    (property "Author" "Antmicro")
    (property "License" "Apache-2.0")
    (property "MPN" "LT8350RV#PBF")
    (property "Manufacturer" "Analog Devices")
    (property "Sheetfile" "power.kicad_sch")
    (property "Sheetname" "Power")
    (property "ki_description" "DC/DC converter")
    (property "ki_keywords" "SMT, PMIC, IC, POWER, MANAGEMENT, VOLTAGE, REGULATOR")
    (attr smd)
    (fp_text reference "U1" (at 0 -3.5 unlocked) (layer "F.SilkS")
        (effects (font (size 0.7 0.7) (thickness 0.15)) (justify left bottom))
    )
    (fp_text value "LT8350RV" (at 0 4.25 unlocked) (layer "F.Fab")
        (effects (font (size 0.7 0.7) (thickness 0.15)) (justify left bottom))
    )
    (fp_text user "Author: Antmicro" (at -2.54 8.65) (layer "F.Fab") hide
        (effects (font (size 0.7 0.7) (thickness 0.15)) (justify left bottom))
    )
    (fp_text user "${REFERENCE}" (at -2.54 7.45 unlocked) (layer "F.Fab") hide
        (effects (font (size 0.7 0.7) (thickness 0.15)) (justify left bottom))
    )
    (fp_text user "License: Apache-2.0" (at -2.54 6.25) (layer "F.Fab") hide
        (effects (font (size 0.7 0.7) (thickness 0.15)) (justify left bottom))
    )
    (fp_line (start -2 -1) (end -2 -0.5)
      (stroke (width 0.15) (type solid)) (layer "F.SilkS"))
    (fp_line (start 2 -2.5) (end 2 -2)
      (stroke (width 0.15) (type solid)) (layer "F.SilkS"))
    (fp_line (start 2 -1) (end 2 -0.5)
      (stroke (width 0.15) (type solid)) (layer "F.SilkS"))
    (fp_circle (center -2.15 -2.05) (end -2.1 -2.05)
      (stroke (width 0.15) (type solid)) (fill none) (layer "F.SilkS"))
    (fp_rect (start -2.3 -3.3) (end 2.3 3.3)
      (stroke (width 0.05) (type solid)) (fill none) (layer "F.CrtYd"))
    (fp_line (start -2 -2) (end -2 3)
      (stroke (width 0.15) (type solid)) (layer "F.Fab"))
    (fp_line (start -2 3) (end -2 3)
      (stroke (width 0.15) (type solid)) (layer "F.Fab"))
    (fp_line (start -2 3) (end 2 3)
      (stroke (width 0.15) (type solid)) (layer "F.Fab"))
    (fp_line (start -1 -3) (end -2 -2)
      (stroke (width 0.15) (type solid)) (layer "F.Fab"))
    (fp_line (start 2 -3) (end -1 -3)
      (stroke (width 0.15) (type solid)) (layer "F.Fab"))
    (fp_line (start 2 3) (end 2 -3)
      (stroke (width 0.15) (type solid)) (layer "F.Fab"))
    (pad "2" smd rect (at -1.899 -1.75) (size 0.7 0.25) (layers "F.Cu" "F.Paste" "F.Mask")
      (net 74 "Net-(C10-Pad2)") (pinfunction "VIN") (pintype "power_in"))
    (pad "3" smd rect (at -1.899 -1.25) (size 0.7 0.25) (layers "F.Cu" "F.Paste" "F.Mask")
      (net 74 "Net-(C10-Pad2)") (pinfunction "VIN") (pintype "passive"))
    (pad "5" smd rect (at -1.899 -0.25) (size 0.7 0.25) (layers "F.Cu" "F.Paste" "F.Mask")
      (net 88 "/Power/DCDC_EN") (pinfunction "EN/UVLO") (pintype "input"))
    (pad "6" smd rect (at -1.899 0.25) (size 0.7 0.25) (layers "F.Cu" "F.Paste" "F.Mask")
      (net 91 "Net-(U1-INTVCC)") (pinfunction "INTVCC") (pintype "power_out"))
    (pad "7" smd rect (at -1.899 0.75) (size 0.7 0.25) (layers "F.Cu" "F.Paste" "F.Mask")
      (net 91 "Net-(U1-INTVCC)") (pinfunction "RP") (pintype "unspecified"))
    (pad "8" smd rect (at -1.899 1.25) (size 0.7 0.25) (layers "F.Cu" "F.Paste" "F.Mask")
      (net 148 "Net-(U1-LOADEN)") (pinfunction "LOADEN") (pintype "input"))
    (pad "9" smd rect (at -1.899 1.75) (size 0.7 0.25) (layers "F.Cu" "F.Paste" "F.Mask")
      (net 5 "Net-(U1-VREF)") (pinfunction "VREF") (pintype "power_out"))
    (pad "10" smd rect (at -1.899 2.25) (size 0.7 0.25) (layers "F.Cu" "F.Paste" "F.Mask")
      (net 206 "Net-(U1-ISMON)") (pinfunction "ISMON") (pintype "output"))
    (pad "11" smd rect (at -1.25 2.9 90) (size 0.7 0.25) (layers "F.Cu" "F.Paste" "F.Mask")
      (net 84 "/Power/I_SENSE_P") (pinfunction "ISP") (pintype "input"))
    (pad "12" smd rect (at -0.75 2.9 90) (size 0.7 0.25) (layers "F.Cu" "F.Paste" "F.Mask")
      (net 85 "/Power/I_SENSE_N") (pinfunction "ISN") (pintype "input"))
    (pad "13" smd rect (at -0.25 2.9 90) (size 0.7 0.25) (layers "F.Cu" "F.Paste" "F.Mask")
      (net 147 "Net-(U1-CTRL)") (pinfunction "CTRL") (pintype "input"))
    (pad "14" smd rect (at 0.25 2.9 90) (size 0.7 0.25) (layers "F.Cu" "F.Paste" "F.Mask")
      (net 169 "Net-(U1-FB)") (pinfunction "FB") (pintype "input"))
    (pad "15" smd rect (at 0.75 2.9 90) (size 0.7 0.25) (layers "F.Cu" "F.Paste" "F.Mask")
      (net 160 "Net-(U1-VC)") (pinfunction "VC") (pintype "output"))
    (pad "16" smd rect (at 1.25 2.9 90) (size 0.7 0.25) (layers "F.Cu" "F.Paste" "F.Mask")
      (net 157 "Net-(U1-~{PGOOD})") (pinfunction "~{PGOOD}") (pintype "open_collector"))
    (pad "17" smd rect (at 1.899 2.25) (size 0.7 0.25) (layers "F.Cu" "F.Paste" "F.Mask")
      (net 92 "Net-(U1-SS)") (pinfunction "SS") (pintype "input"))
    (pad "18" smd rect (at 1.899 1.75) (size 0.7 0.25) (layers "F.Cu" "F.Paste" "F.Mask")
      (net 161 "Net-(U1-RT)") (pinfunction "RT") (pintype "input"))
    (pad "19" smd rect (at 1.899 1.25) (size 0.7 0.25) (layers "F.Cu" "F.Paste" "F.Mask")
      (net 159 "Net-(U1-SYNC{slash}MODE)") (pinfunction "SYNC/MODE") (pintype "input"))
    (pad "20" smd rect (at 1.899 0.75) (size 0.7 0.25) (layers "F.Cu" "F.Paste" "F.Mask")
      (net 207 "Net-(U1-CLKOUT)") (pinfunction "CLKOUT") (pintype "output"))
    (pad "21" smd rect (at 1.899 0.25) (size 0.7 0.25) (layers "F.Cu" "F.Paste" "F.Mask")
      (net 97 "Net-(U1-EXTVCC)") (pinfunction "EXTVCC") (pintype "power_in"))
    (pad "22" smd rect (at 1.899 -0.25) (size 0.7 0.25) (layers "F.Cu" "F.Paste" "F.Mask")
      (net 205 "Net-(U1-LOADTG)") (pinfunction "LOADTG") (pintype "output"))
    (pad "24" smd rect (at 1.899 -1.25) (size 0.7 0.25) (layers "F.Cu" "F.Paste" "F.Mask")
      (net 75 "Net-(C32-Pad2)") (pinfunction "VOUT") (pintype "power_out"))
    (pad "25" smd rect (at 1.899 -1.75) (size 0.7 0.25) (layers "F.Cu" "F.Paste" "F.Mask")
      (net 75 "Net-(C32-Pad2)") (pinfunction "VOUT") (pintype "passive"))
    (pad "27" smd rect (at 1.25 -2.9 90) (size 0.7 0.25) (layers "F.Cu" "F.Paste" "F.Mask")
      (net 268 "Net-(C28-Pad2)") (pinfunction "SW2") (pintype "output"))
    (pad "28" smd rect (at 0.75 -2.9 90) (size 0.7 0.25) (layers "F.Cu" "F.Paste" "F.Mask")
      (net 268 "Net-(C28-Pad2)") (pinfunction "SW2") (pintype "passive"))
    (pad "29" smd rect (at 0.25 -2.9 90) (size 0.7 0.25) (layers "F.Cu" "F.Paste" "F.Mask")
      (net 96 "Net-(U1-BST2)") (pinfunction "BST2") (pintype "input"))
    (pad "30" smd rect (at -0.25 -2.9 90) (size 0.7 0.25) (layers "F.Cu" "F.Paste" "F.Mask")
      (net 93 "Net-(U1-BST1)") (pinfunction "BST1") (pintype "input"))
    (pad "31" smd rect (at -0.75 -2.9 90) (size 0.7 0.25) (layers "F.Cu" "F.Paste" "F.Mask")
      (net 4 "Net-(C26-Pad2)") (pinfunction "SW1") (pintype "output"))
    (pad "32" smd rect (at -1.25 -2.9 90) (size 0.7 0.25) (layers "F.Cu" "F.Paste" "F.Mask")
      (net 4 "Net-(C26-Pad2)") (pinfunction "SW1") (pintype "passive"))
    (pad "33" smd rect (at -0.696 -1.055 90) (size 1.91 1.2) (layers "F.Cu" "F.Paste" "F.Mask")
      (net 1 "GND") (pinfunction "GND") (pintype "power_in"))
    (pad "34" smd rect (at 0.696 -1.055 90) (size 1.91 1.2) (layers "F.Cu" "F.Paste" "F.Mask")
      (net 1 "GND") (pinfunction "GND") (pintype "passive"))
    (pad "35" smd rect (at -0.696 1.055 90) (size 1.91 1.2) (layers "F.Cu" "F.Paste" "F.Mask")
      (net 1 "GND") (pinfunction "GND") (pintype "passive"))
    (pad "36" smd rect (at 0.696 1.055 90) (size 1.91 1.2) (layers "F.Cu" "F.Paste" "F.Mask")
      (net 1 "GND") (pinfunction "GND") (pintype "passive"))
    (pad "MP" smd rect (at -1.812 -2.812 90) (size 0.375 0.375) (layers "F.Cu" "F.Paste" "F.Mask")
      (net 1 "GND") (pinfunction "MP") (pintype "passive"))
    (pad "MP" smd rect (at -1.812 2.812 90) (size 0.375 0.375) (layers "F.Cu" "F.Paste" "F.Mask")
      (net 1 "GND") (pinfunction "MP") (pintype "passive"))
    (pad "MP" smd rect (at 1.812 -2.812 90) (size 0.375 0.375) (layers "F.Cu" "F.Paste" "F.Mask")
      (net 1 "GND") (pinfunction "MP") (pintype "passive"))
    (pad "MP" smd rect (at 1.812 2.812 90) (size 0.375 0.375) (layers "F.Cu" "F.Paste" "F.Mask")
      (net 1 "GND") (pinfunction "MP") (pintype "passive"))
  )
	(footprint "antmicro-footprints:MP_Pad6mm_Drill3mm" (layer "F.Cu")
    (at 166 96)
    (property "Author" "Antmicro")
    (property "License" "Apache-2.0")
    (property "Sheetfile" "connectors.kicad_sch")
    (property "Sheetname" "Connectors")
    (property "exclude_from_bom" "")
    (property "ki_description" "Mechanical part")
    (property "ki_keywords" "MECHANICAL")
    (attr exclude_from_pos_files exclude_from_bom)
    (fp_text reference "MP3" (at 0 -3.2) (layer "F.SilkS") hide
        (effects (font (size 0.7 0.7) (thickness 0.15)) (justify left bottom))
    )
    (fp_text value "MP_Pad6mm_Drill3mm" (at 0 3.9) (layer "F.Fab")
        (effects (font (size 0.7 0.7) (thickness 0.15)) (justify left bottom))
    )
    (fp_text user "${REFERENCE}" (at -0.178 6.025) (layer "F.Fab") hide
        (effects (font (size 0.7 0.7) (thickness 0.15)) (justify left bottom))
    )
    (fp_text user "License: Apache-2.0" (at -0.178 8.425) (layer "F.Fab") hide
        (effects (font (size 0.7 0.7) (thickness 0.15)) (justify left bottom))
    )
    (fp_text user "Author: Antmicro" (at -0.178 7.225) (layer "F.Fab") hide
        (effects (font (size 0.7 0.7) (thickness 0.15)) (justify left bottom))
    )
    (fp_circle (center 0 0) (end 3.25 0)
      (stroke (width 0.05) (type default)) (fill none) (layer "F.CrtYd"))
    (pad "1" thru_hole circle (at 0 0) (size 6 6) (drill 3) (layers "*.Cu" "*.Mask")
      (net 1 "GND") (pintype "passive"))
  )
	(footprint "antmicro-footprints:C_0603_1608Metric" (layer "F.Cu")
    (at 117.085001 79.9 -90)
    (descr "Capacitor SMD 0603")
    (tags "capacitor 0603")
    (property "Author" "Antmicro")
    (property "Dielectric" "")
    (property "License" "Apache-2.0")
    (property "MPN" "CL10A226MO7JZNC")
    (property "Manufacturer" "Samsung Electro-Mechanics")
    (property "Sheetfile" "power.kicad_sch")
    (property "Sheetname" "Power")
    (property "Val" "22u")
    (property "Voltage" "16V")
    (property "ki_description" "SMD Multilayer Ceramic Capacitor")
    (property "ki_keywords" "0603, SMT, CAPACITOR, PASSIVE, CERAMIC")
    (attr smd)
    (fp_text reference "C46" (at -1.16 -0.340998 -90) (layer "F.SilkS")
        (effects (font (size 0.7 0.7) (thickness 0.15)) (justify left bottom))
    )
    (fp_text value "C_22u_16V_0603" (at -1.42757 1.770288 -90) (layer "F.Fab")
        (effects (font (size 0.7 0.7) (thickness 0.15)) (justify left bottom))
    )
    (fp_text user "License: Apache-2.0" (at -1.682 5.895 -90) (layer "F.Fab") hide
        (effects (font (size 0.7 0.7) (thickness 0.15)) (justify left bottom))
    )
    (fp_text user "${REFERENCE}" (at -1.682 3.895 -90) (layer "F.Fab") hide
        (effects (font (size 0.7 0.7) (thickness 0.15)) (justify left bottom))
    )
    (fp_text user "Author: Antmicro" (at -1.682 4.894 -90) (layer "F.Fab") hide
        (effects (font (size 0.7 0.7) (thickness 0.15)) (justify left bottom))
    )
    (fp_line (start -0.15 -0.4) (end 0.15 -0.4)
      (stroke (width 0.15) (type solid)) (layer "F.SilkS"))
    (fp_line (start -0.15 0.4) (end 0.15 0.4)
      (stroke (width 0.15) (type solid)) (layer "F.SilkS"))
    (fp_rect (start -1.25 -0.65) (end 1.25 0.65)
      (stroke (width 0.05) (type solid)) (fill none) (layer "F.CrtYd"))
    (fp_rect (start -0.8 -0.4) (end 0.8 0.4)
      (stroke (width 0.15) (type solid)) (fill none) (layer "F.Fab"))
    (pad "1" smd roundrect (at -0.7 0 270) (size 0.8 1) (layers "F.Cu" "F.Paste" "F.Mask") (roundrect_rratio 0.2)
      (net 1 "GND") (pintype "passive"))
    (pad "2" smd roundrect (at 0.7 0 270) (size 0.8 1) (layers "F.Cu" "F.Paste" "F.Mask") (roundrect_rratio 0.2)
      (net 75 "Net-(C32-Pad2)") (pintype "passive"))
  )
	(footprint "antmicro-footprints:SOT-323" (layer "F.Cu")
    (at 147.5 70.94)
    (property "Author" "Antmicro")
    (property "License" "Apache-2.0")
    (property "MPN" "BC817-25W,115")
    (property "Manufacturer" "Nexperia")
    (property "Sheetfile" "tb-power.kicad_sch")
    (property "Sheetname" "Thunderbolt Controller - Power")
    (property "ki_description" "Bipolar (BJT) Single Transistor, NPN, 45 V, 500 mA, 200 mW, SOT-323, Surface Mount")
    (property "ki_keywords" "SMT, TRANSISTOR, SEMICONDUCTOR, BIPOLAR")
    (attr smd)
    (fp_text reference "Q1" (at 1.471 0.434) (layer "F.SilkS")
        (effects (font (size 0.7 0.7) (thickness 0.15)) (justify left bottom))
    )
    (fp_text value "BC817-25W" (at 0 2.749) (layer "F.Fab")
        (effects (font (size 0.7 0.7) (thickness 0.15)) (justify left bottom))
    )
    (fp_text user "${REFERENCE}" (at -1.35 4.749) (layer "F.Fab") hide
        (effects (font (size 0.7 0.7) (thickness 0.15)) (justify left bottom))
    )
    (fp_text user "License: Apache-2.0" (at -1.35 5.949) (layer "F.Fab") hide
        (effects (font (size 0.7 0.7) (thickness 0.15)) (justify left bottom))
    )
    (fp_text user "Author: Antmicro" (at -1.35 7.149) (layer "F.Fab") hide
        (effects (font (size 0.7 0.7) (thickness 0.15)) (justify left bottom))
    )
    (fp_line (start -0.802 -1.2) (end -0.802 -1.05)
      (stroke (width 0.15) (type solid)) (layer "F.SilkS"))
    (fp_line (start -0.802 1.05) (end -0.802 1.199)
      (stroke (width 0.15) (type solid)) (layer "F.SilkS"))
    (fp_line (start -0.802 1.199) (end -0.5 1.199)
      (stroke (width 0.15) (type solid)) (layer "F.SilkS"))
    (fp_line (start -0.402 -1.2) (end -0.802 -1.2)
      (stroke (width 0.15) (type solid)) (layer "F.SilkS"))
    (fp_line (start 0.498 -1.2) (end 0.8 -1.2)
      (stroke (width 0.15) (type solid)) (layer "F.SilkS"))
    (fp_line (start 0.498 1.199) (end 0.8 1.199)
      (stroke (width 0.15) (type solid)) (layer "F.SilkS"))
    (fp_line (start 0.8 -1.2) (end 0.8 -0.902)
      (stroke (width 0.15) (type solid)) (layer "F.SilkS"))
    (fp_line (start 0.8 1.199) (end 0.8 0.9)
      (stroke (width 0.15) (type solid)) (layer "F.SilkS"))
    (fp_circle (center -1.05 -1.156824) (end -1 -1.129824)
      (stroke (width 0.15) (type solid)) (fill none) (layer "F.SilkS"))
    (fp_rect (start -1.35 -1.35) (end 1.35 1.35)
      (stroke (width 0.05) (type solid)) (fill none) (layer "F.CrtYd"))
    (fp_line (start -0.677 -1.101) (end -0.677 1.1)
      (stroke (width 0.15) (type solid)) (layer "F.Fab"))
    (fp_line (start -0.677 -1.101) (end 0.675 -1.101)
      (stroke (width 0.15) (type solid)) (layer "F.Fab"))
    (fp_line (start -0.677 1.1) (end 0.675 1.1)
      (stroke (width 0.15) (type solid)) (layer "F.Fab"))
    (fp_line (start 0.675 -1.101) (end 0.675 1.1)
      (stroke (width 0.15) (type solid)) (layer "F.Fab"))
    (pad "1" smd rect (at -0.927 -0.652) (size 0.55 0.6) (layers "F.Cu" "F.Paste" "F.Mask")
      (net 138 "Net-(Q1-B)") (pinfunction "B") (pintype "input"))
    (pad "2" smd rect (at -0.927 0.65) (size 0.55 0.6) (layers "F.Cu" "F.Paste" "F.Mask")
      (net 1 "GND") (pinfunction "E") (pintype "passive"))
    (pad "3" smd rect (at 0.925 0) (size 0.55 0.6) (layers "F.Cu" "F.Paste" "F.Mask")
      (net 139 "Net-(Q1-C)") (pinfunction "C") (pintype "passive"))
  )
	(footprint "antmicro-footprints:C_0603_1608Metric" (layer "F.Cu")
    (at 142.9 72.3 90)
    (descr "Capacitor SMD 0603")
    (tags "capacitor 0603")
    (property "Author" "Antmicro")
    (property "Dielectric" "")
    (property "License" "Apache-2.0")
    (property "MPN" "GRM188R60J226MEA0D")
    (property "Manufacturer" "Murata")
    (property "Sheetfile" "tb-power.kicad_sch")
    (property "Sheetname" "Thunderbolt Controller - Power")
    (property "Val" "22u")
    (property "Voltage" "")
    (property "ki_description" "SMD Multilayer Ceramic Capacitor, 22 µF, 6.3 V, 0603 [1608 Metric], ± 20%, X5R, GRM Series")
    (property "ki_keywords" "0603, SMT, CAPACITOR, PASSIVE, CERAMIC, MLCC")
    (attr smd)
    (fp_text reference "C82" (at -3.519 0.483 90) (layer "F.SilkS")
        (effects (font (size 0.7 0.7) (thickness 0.15)) (justify left bottom))
    )
    (fp_text value "C_22u_0603" (at -1.42757 1.770288 90) (layer "F.Fab")
        (effects (font (size 0.7 0.7) (thickness 0.15)) (justify left bottom))
    )
    (fp_text user "License: Apache-2.0" (at -1.682 5.895 90) (layer "F.Fab") hide
        (effects (font (size 0.7 0.7) (thickness 0.15)) (justify left bottom))
    )
    (fp_text user "Author: Antmicro" (at -1.682 4.894 90) (layer "F.Fab") hide
        (effects (font (size 0.7 0.7) (thickness 0.15)) (justify left bottom))
    )
    (fp_text user "${REFERENCE}" (at -1.682 3.895 90) (layer "F.Fab") hide
        (effects (font (size 0.7 0.7) (thickness 0.15)) (justify left bottom))
    )
    (fp_line (start -0.15 -0.4) (end 0.15 -0.4)
      (stroke (width 0.15) (type solid)) (layer "F.SilkS"))
    (fp_line (start -0.15 0.4) (end 0.15 0.4)
      (stroke (width 0.15) (type solid)) (layer "F.SilkS"))
    (fp_rect (start -1.25 -0.65) (end 1.25 0.65)
      (stroke (width 0.05) (type solid)) (fill none) (layer "F.CrtYd"))
    (fp_rect (start -0.8 -0.4) (end 0.8 0.4)
      (stroke (width 0.15) (type solid)) (fill none) (layer "F.Fab"))
    (pad "1" smd roundrect (at -0.7 0 90) (size 0.8 1) (layers "F.Cu" "F.Paste" "F.Mask") (roundrect_rratio 0.2)
      (net 1 "GND") (pintype "passive"))
    (pad "2" smd roundrect (at 0.7 0 90) (size 0.8 1) (layers "F.Cu" "F.Paste" "F.Mask") (roundrect_rratio 0.2)
      (net 112 "Net-(U4A-VCC0P9_SVR_SENSE)") (pintype "passive"))
  )
)
